(kicad_pcb
	(version 20260206)
	(generator "pcbnew")
	(generator_version "10.0")
	(general
		(thickness 1.6)
		(legacy_teardrops no)
	)
	(paper "A4")
	(title_block
		(title "03242023_DA0F0TMBIJ0_F0T_Motherboard_J_brd_V01_OCP.brd")
		(comment 1 "Grand Teton / footprints 5374-5379 of 6105")
	)
	(layers
		(0 "F.Cu" signal "TOP")
		(4 "In1.Cu" signal "GND")
		(6 "In2.Cu" signal "IN1")
		(8 "In3.Cu" signal "GND1")
		(10 "In4.Cu" signal "IN2")
		(12 "In5.Cu" signal "GND2")
		(14 "In6.Cu" signal "IN3")
		(16 "In7.Cu" signal "GND3")
		(18 "In8.Cu" signal "VCC")
		(20 "In9.Cu" signal "VCC1")
		(22 "In10.Cu" signal "GND4")
		(24 "In11.Cu" signal "IN4")
		(26 "In12.Cu" signal "GND5")
		(28 "In13.Cu" signal "IN5")
		(30 "In14.Cu" signal "GND6")
		(32 "In15.Cu" signal "IN6")
		(34 "In16.Cu" signal "GND7")
		(2 "B.Cu" signal "BOTTOM")
		(9 "F.Adhes" user "F.Adhesive")
		(11 "B.Adhes" user "B.Adhesive")
		(13 "F.Paste" user "Package Geometry/Pastemask Top")
		(15 "B.Paste" user "Package Geometry/Pastemask Bottom")
		(5 "F.SilkS" user "Ref Des/Silkscreen Top")
		(7 "B.SilkS" user "Ref Des/Silkscreen Bottom")
		(1 "F.Mask" user "Board Geometry/Soldermask Top")
		(3 "B.Mask" user "Board Geometry/Soldermask Bottom")
		(17 "Dwgs.User" user "User.Drawings")
		(19 "Cmts.User" user "User.Comments")
		(21 "Eco1.User" user "User.Eco1")
		(23 "Eco2.User" user "User.Eco2")
		(25 "Edge.Cuts" user "Board Geometry/Outline")
		(27 "Margin" user)
		(31 "F.CrtYd" user "Package Geometry/Place Bound Top")
		(29 "B.CrtYd" user "Package Geometry/Place Bound Bottom")
		(35 "F.Fab" user "Ref Des/Assembly Top")
		(33 "B.Fab" user "Ref Des/Assembly Bottom")
	)
	(footprint ""
		(layer "B.Cu")
		(at 181.530752 -192.699894 -90)
		(property "Reference" "R325"
			(at 0 0 90)
			(layer "B.SilkS")
			(hide yes)
			(effects
				(font
					(size 1.27 1.27)
				)
				(justify mirror)
			)
		)
		(property "Value" ""
			(at 0 0 90)
			(layer "B.Fab")
			(effects
				(font
					(size 1.27 1.27)
				)
				(justify mirror)
			)
		)
		(duplicate_pad_numbers_are_jumpers no)
		(fp_line
			(start -0.7874 0.4064)
			(end 0.7874 0.4064)
			(stroke
				(width 0.1524)
				(type default)
			)
			(layer "B.SilkS")
		)
		(fp_line
			(start 0.7874 0.4064)
			(end 0.7874 -0.4064)
			(stroke
				(width 0.1524)
				(type default)
			)
			(layer "B.SilkS")
		)
		(fp_line
			(start -0.7874 -0.4064)
			(end -0.7874 0.4064)
			(stroke
				(width 0.1524)
				(type default)
			)
			(layer "B.SilkS")
		)
		(fp_line
			(start 0.7874 -0.4064)
			(end -0.7874 -0.4064)
			(stroke
				(width 0.1524)
				(type default)
			)
			(layer "B.SilkS")
		)
		(fp_line
			(start -0.67945 0.3048)
			(end -0.120396 0.3048)
			(stroke
				(width 0.1)
				(type default)
			)
			(layer "B.Fab")
		)
		(fp_line
			(start -0.120396 0.3048)
			(end -0.120396 0.2794)
			(stroke
				(width 0.1)
				(type default)
			)
			(layer "B.Fab")
		)
		(fp_line
			(start 0.12065 0.3048)
			(end 0.67945 0.3048)
			(stroke
				(width 0.1)
				(type default)
			)
			(layer "B.Fab")
		)
		(fp_line
			(start 0.67945 0.3048)
			(end 0.67945 -0.305054)
			(stroke
				(width 0.1)
				(type default)
			)
			(layer "B.Fab")
		)
		(fp_line
			(start -0.120396 0.2794)
			(end 0.12065 0.2794)
			(stroke
				(width 0.1)
				(type default)
			)
			(layer "B.Fab")
		)
		(fp_line
			(start 0.12065 0.2794)
			(end 0.12065 0.3048)
			(stroke
				(width 0.1)
				(type default)
			)
			(layer "B.Fab")
		)
		(fp_line
			(start -0.12065 -0.2794)
			(end -0.12065 -0.3048)
			(stroke
				(width 0.1)
				(type default)
			)
			(layer "B.Fab")
		)
		(fp_line
			(start 0.12065 -0.2794)
			(end -0.12065 -0.2794)
			(stroke
				(width 0.1)
				(type default)
			)
			(layer "B.Fab")
		)
		(fp_line
			(start -0.67945 -0.3048)
			(end -0.67945 0.3048)
			(stroke
				(width 0.1)
				(type default)
			)
			(layer "B.Fab")
		)
		(fp_line
			(start -0.12065 -0.3048)
			(end -0.67945 -0.3048)
			(stroke
				(width 0.1)
				(type default)
			)
			(layer "B.Fab")
		)
		(fp_line
			(start 0.12065 -0.305054)
			(end 0.12065 -0.2794)
			(stroke
				(width 0.1)
				(type default)
			)
			(layer "B.Fab")
		)
		(fp_line
			(start 0.67945 -0.305054)
			(end 0.12065 -0.305054)
			(stroke
				(width 0.1)
				(type default)
			)
			(layer "B.Fab")
		)
		(pad "1" smd circle
			(at 0.40005 0 90)
			(size 0 0)
			(layers "B.Cu" "B.Mask" "B.Paste")
			(net "P3V3_AUX")
		)
		(pad "2" smd circle
			(at -0.40005 0 90)
			(size 0 0)
			(layers "B.Cu" "B.Mask" "B.Paste")
			(net "PU_S3M_CPU1_CPLD_STATUS")
		)
	)
	(footprint ""
		(layer "B.Cu")
		(at 331.873352 -342.936576 90)
		(property "Reference" "PC237_P0_7"
			(at 0 0 90)
			(layer "B.SilkS")
			(hide yes)
			(effects
				(font
					(size 1.27 1.27)
				)
				(justify mirror)
			)
		)
		(property "Value" ""
			(at 0 0 90)
			(layer "B.Fab")
			(effects
				(font
					(size 1.27 1.27)
				)
				(justify mirror)
			)
		)
		(duplicate_pad_numbers_are_jumpers no)
		(fp_line
			(start 1.524 -0.762)
			(end -1.524 -0.762)
			(stroke
				(width 0.1524)
				(type default)
			)
			(layer "B.SilkS")
		)
		(fp_line
			(start -1.524 -0.762)
			(end -1.524 0.762)
			(stroke
				(width 0.1524)
				(type default)
			)
			(layer "B.SilkS")
		)
		(fp_line
			(start 1.524 0.762)
			(end 1.524 -0.762)
			(stroke
				(width 0.1524)
				(type default)
			)
			(layer "B.SilkS")
		)
		(fp_line
			(start -1.524 0.762)
			(end 1.524 0.762)
			(stroke
				(width 0.1524)
				(type default)
			)
			(layer "B.SilkS")
		)
		(fp_line
			(start 1.1049 -0.724916)
			(end 1.1049 0.724916)
			(stroke
				(width 0.1)
				(type default)
			)
			(layer "B.Fab")
		)
		(fp_line
			(start -1.1049 -0.724916)
			(end 1.1049 -0.724916)
			(stroke
				(width 0.1)
				(type default)
			)
			(layer "B.Fab")
		)
		(fp_line
			(start 1.1049 0.724916)
			(end -1.1049 0.724916)
			(stroke
				(width 0.1)
				(type default)
			)
			(layer "B.Fab")
		)
		(fp_line
			(start -1.1049 0.724916)
			(end -1.1049 -0.724916)
			(stroke
				(width 0.1)
				(type default)
			)
			(layer "B.Fab")
		)
		(pad "1" smd rect
			(at 0.889 0 90)
			(size 1.016 1.27)
			(layers "B.Cu" "B.Mask" "B.Paste")
			(net "SW_P12V_PVCCIN_CPU0_FLT")
		)
		(pad "2" smd rect
			(at -0.889 0 90)
			(size 1.016 1.27)
			(layers "B.Cu" "B.Mask" "B.Paste")
			(net "GND")
		)
	)
	(footprint ""
		(layer "B.Cu")
		(at 167.078152 -318.23533)
		(property "Reference" "R901"
			(at 0 0 0)
			(layer "B.SilkS")
			(hide yes)
			(effects
				(font
					(size 1.27 1.27)
				)
				(justify mirror)
			)
		)
		(property "Value" ""
			(at 0 0 0)
			(layer "B.Fab")
			(effects
				(font
					(size 1.27 1.27)
				)
				(justify mirror)
			)
		)
		(duplicate_pad_numbers_are_jumpers no)
		(fp_line
			(start -0.7874 -0.4064)
			(end -0.7874 0.4064)
			(stroke
				(width 0.1524)
				(type default)
			)
			(layer "B.SilkS")
		)
		(fp_line
			(start -0.7874 0.4064)
			(end 0.7874 0.4064)
			(stroke
				(width 0.1524)
				(type default)
			)
			(layer "B.SilkS")
		)
		(fp_line
			(start 0.7874 -0.4064)
			(end -0.7874 -0.4064)
			(stroke
				(width 0.1524)
				(type default)
			)
			(layer "B.SilkS")
		)
		(fp_line
			(start 0.7874 0.4064)
			(end 0.7874 -0.4064)
			(stroke
				(width 0.1524)
				(type default)
			)
			(layer "B.SilkS")
		)
		(fp_line
			(start -0.67945 -0.3048)
			(end -0.67945 0.3048)
			(stroke
				(width 0.1)
				(type default)
			)
			(layer "B.Fab")
		)
		(fp_line
			(start -0.67945 0.3048)
			(end -0.120396 0.3048)
			(stroke
				(width 0.1)
				(type default)
			)
			(layer "B.Fab")
		)
		(fp_line
			(start -0.12065 -0.3048)
			(end -0.67945 -0.3048)
			(stroke
				(width 0.1)
				(type default)
			)
			(layer "B.Fab")
		)
		(fp_line
			(start -0.12065 -0.2794)
			(end -0.12065 -0.3048)
			(stroke
				(width 0.1)
				(type default)
			)
			(layer "B.Fab")
		)
		(fp_line
			(start -0.120396 0.2794)
			(end 0.12065 0.2794)
			(stroke
				(width 0.1)
				(type default)
			)
			(layer "B.Fab")
		)
		(fp_line
			(start -0.120396 0.3048)
			(end -0.120396 0.2794)
			(stroke
				(width 0.1)
				(type default)
			)
			(layer "B.Fab")
		)
		(fp_line
			(start 0.12065 -0.305054)
			(end 0.12065 -0.2794)
			(stroke
				(width 0.1)
				(type default)
			)
			(layer "B.Fab")
		)
		(fp_line
			(start 0.12065 -0.2794)
			(end -0.12065 -0.2794)
			(stroke
				(width 0.1)
				(type default)
			)
			(layer "B.Fab")
		)
		(fp_line
			(start 0.12065 0.2794)
			(end 0.12065 0.3048)
			(stroke
				(width 0.1)
				(type default)
			)
			(layer "B.Fab")
		)
		(fp_line
			(start 0.12065 0.3048)
			(end 0.67945 0.3048)
			(stroke
				(width 0.1)
				(type default)
			)
			(layer "B.Fab")
		)
		(fp_line
			(start 0.67945 -0.305054)
			(end 0.12065 -0.305054)
			(stroke
				(width 0.1)
				(type default)
			)
			(layer "B.Fab")
		)
		(fp_line
			(start 0.67945 0.3048)
			(end 0.67945 -0.305054)
			(stroke
				(width 0.1)
				(type default)
			)
			(layer "B.Fab")
		)
		(pad "1" smd circle
			(at 0.40005 0 180)
			(size 0 0)
			(layers "B.Cu" "B.Mask" "B.Paste")
			(net "PWRGD_CHE_CPU1_DIMM1")
		)
		(pad "2" smd circle
			(at -0.40005 0 180)
			(size 0 0)
			(layers "B.Cu" "B.Mask" "B.Paste")
			(net "PWRGD_FAIL_CPU1_EF")
		)
	)
	(footprint ""
		(layer "B.Cu")
		(at 173.04893 -101.564948 180)
		(property "Reference" "R3349"
			(at 0 0 0)
			(layer "B.SilkS")
			(hide yes)
			(effects
				(font
					(size 1.27 1.27)
				)
				(justify mirror)
			)
		)
		(property "Value" ""
			(at 0 0 0)
			(layer "B.Fab")
			(effects
				(font
					(size 1.27 1.27)
				)
				(justify mirror)
			)
		)
		(duplicate_pad_numbers_are_jumpers no)
		(fp_line
			(start 1.2954 0.5842)
			(end 1.2954 -0.5842)
			(stroke
				(width 0.1524)
				(type default)
			)
			(layer "B.SilkS")
		)
		(fp_line
			(start 1.2954 -0.5842)
			(end -1.2954 -0.5842)
			(stroke
				(width 0.1524)
				(type default)
			)
			(layer "B.SilkS")
		)
		(fp_line
			(start -1.2954 0.5842)
			(end 1.2954 0.5842)
			(stroke
				(width 0.1524)
				(type default)
			)
			(layer "B.SilkS")
		)
		(fp_line
			(start -1.2954 -0.5842)
			(end -1.2954 0.5842)
			(stroke
				(width 0.1524)
				(type default)
			)
			(layer "B.SilkS")
		)
		(fp_line
			(start 1.1938 0.4064)
			(end 1.1938 -0.406654)
			(stroke
				(width 0.1)
				(type default)
			)
			(layer "B.Fab")
		)
		(fp_line
			(start 1.1938 -0.406654)
			(end 0.8636 -0.406654)
			(stroke
				(width 0.1)
				(type default)
			)
			(layer "B.Fab")
		)
		(fp_line
			(start 0.8636 0.4572)
			(end 0.8636 0.4318)
			(stroke
				(width 0.1)
				(type default)
			)
			(layer "B.Fab")
		)
		(fp_line
			(start 0.8636 0.4318)
			(end 0.8636 0.4064)
			(stroke
				(width 0.1)
				(type default)
			)
			(layer "B.Fab")
		)
		(fp_line
			(start 0.8636 0.4064)
			(end 1.1938 0.4064)
			(stroke
				(width 0.1)
				(type default)
			)
			(layer "B.Fab")
		)
		(fp_line
			(start 0.8636 -0.406654)
			(end 0.8636 -0.4572)
			(stroke
				(width 0.1)
				(type default)
			)
			(layer "B.Fab")
		)
		(fp_line
			(start 0.8636 -0.4572)
			(end -0.8636 -0.4572)
			(stroke
				(width 0.1)
				(type default)
			)
			(layer "B.Fab")
		)
		(fp_line
			(start -0.8636 0.4572)
			(end 0.8636 0.4572)
			(stroke
				(width 0.1)
				(type default)
			)
			(layer "B.Fab")
		)
		(fp_line
			(start -0.8636 0.4064)
			(end -0.8636 0.4572)
			(stroke
				(width 0.1)
				(type default)
			)
			(layer "B.Fab")
		)
		(fp_line
			(start -0.8636 -0.406654)
			(end -1.1938 -0.406654)
			(stroke
				(width 0.1)
				(type default)
			)
			(layer "B.Fab")
		)
		(fp_line
			(start -0.8636 -0.4572)
			(end -0.8636 -0.406654)
			(stroke
				(width 0.1)
				(type default)
			)
			(layer "B.Fab")
		)
		(fp_line
			(start -1.1938 0.4064)
			(end -0.8636 0.4064)
			(stroke
				(width 0.1)
				(type default)
			)
			(layer "B.Fab")
		)
		(fp_line
			(start -1.1938 -0.406654)
			(end -1.1938 0.4064)
			(stroke
				(width 0.1)
				(type default)
			)
			(layer "B.Fab")
		)
		(pad "1" smd rect
			(at 0.7366 0 90)
			(size 0.7112 0.8128)
			(layers "B.Cu" "B.Mask" "B.Paste")
			(net "P3V3_AUX")
		)
		(pad "2" smd rect
			(at -0.7366 0 90)
			(size 0.7112 0.8128)
			(layers "B.Cu" "B.Mask" "B.Paste")
			(net "P3V3_AUX_FPGA_VCCIO5")
		)
	)
	(footprint ""
		(layer "B.Cu")
		(at 506.598428 -148.08708 -90)
		(property "Reference" "X29"
			(at 3.734816 3.412998 270)
			(unlocked yes)
			(layer "B.SilkS")
			(effects
				(font
					(size 0.7874 0.5842)
					(thickness 0.1524)
				)
				(justify left mirror)
			)
		)
		(property "Value" ""
			(at 0 0 90)
			(layer "B.Fab")
			(effects
				(font
					(size 1.27 1.27)
				)
				(justify mirror)
			)
		)
		(property "Device Type" "TP_TDR_4P_FTS_TH-TP_TDR_4P_DIPA"
			(at -1.30175 1.27 180)
			(unlocked yes)
			(layer "B.Fab")
			(hide yes)
			(effects
				(font
					(size 0.635 0.4064)
					(thickness 0.1524)
				)
				(justify mirror)
			)
		)
		(property "User Part Number" "N_A"
			(at -1.30175 1.27 180)
			(unlocked yes)
			(layer "Cmts.User")
			(hide yes)
			(effects
				(font
					(size 0.635 0.4064)
					(thickness 0.1524)
				)
				(justify mirror)
			)
		)
		(duplicate_pad_numbers_are_jumpers no)
		(fp_line
			(start -2.54 3.81)
			(end -2.54 3.6703)
			(stroke
				(width 0.1524)
				(type default)
			)
			(layer "B.SilkS")
		)
		(fp_line
			(start 0 3.81)
			(end -2.54 3.81)
			(stroke
				(width 0.1524)
				(type default)
			)
			(layer "B.SilkS")
		)
		(fp_line
			(start 0 3.175)
			(end 0 3.81)
			(stroke
				(width 0.1524)
				(type default)
			)
			(layer "B.SilkS")
		)
		(fp_line
			(start -2.54 1.4097)
			(end -2.54 1.1303)
			(stroke
				(width 0.1524)
				(type default)
			)
			(layer "B.SilkS")
		)
		(fp_line
			(start 0 0.635)
			(end 0 1.905)
			(stroke
				(width 0.1524)
				(type default)
			)
			(layer "B.SilkS")
		)
		(fp_line
			(start -2.54 -1.1303)
			(end -2.54 -1.27)
			(stroke
				(width 0.1524)
				(type default)
			)
			(layer "B.SilkS")
		)
		(fp_line
			(start -2.54 -1.27)
			(end 0 -1.27)
			(stroke
				(width 0.1524)
				(type default)
			)
			(layer "B.SilkS")
		)
		(fp_line
			(start 0 -1.27)
			(end 0 -0.635)
			(stroke
				(width 0.1524)
				(type default)
			)
			(layer "B.SilkS")
		)
		(fp_poly
			(pts
				(xy 2.938526 -0.71882) (xy 2.938526 0.80518) (xy 1.414526 0.04318)
			)
			(stroke
				(width 0)
				(type default)
			)
			(fill yes)
			(layer "B.SilkS")
		)
		(fp_line
			(start -2.54 3.81)
			(end -2.54 -1.27)
			(stroke
				(width 0.1)
				(type default)
			)
			(layer "B.Fab")
		)
		(fp_line
			(start 0 3.81)
			(end -2.54 3.81)
			(stroke
				(width 0.1)
				(type default)
			)
			(layer "B.Fab")
		)
		(fp_line
			(start -2.54 -1.27)
			(end 0 -1.27)
			(stroke
				(width 0.1)
				(type default)
			)
			(layer "B.Fab")
		)
		(fp_line
			(start 0 -1.27)
			(end 0 3.81)
			(stroke
				(width 0.1)
				(type default)
			)
			(layer "B.Fab")
		)
		(fp_poly
			(pts
				(xy 0.761746 0) (xy 2.285746 -0.762) (xy 2.285746 0.762)
			)
			(stroke
				(width 0)
				(type default)
			)
			(fill yes)
			(layer "B.Fab")
		)
		(pad "1" thru_hole circle
			(at 0 0 90)
			(size 1.0033 1.0033)
			(drill 0.249936)
			(layers "*.Cu" "*.Mask")
			(remove_unused_layers no)
			(net "TDR_DIFF_100_IN5_DP")
			(clearance 0.10795)
			(padstack
				(mode front_inner_back)
				(layer "Inner"
					(shape circle)
					(size 0.8001 0.8001)
					(clearance 0.1524)
				)
				(layer "B.Cu"
					(shape circle)
					(size 1.0033 1.0033)
					(thermal_gap 0.10795)
					(clearance 0.10795)
				)
			)
		)
		(pad "2" thru_hole circle
			(at -2.54 0 90)
			(size 1.9939 1.9939)
			(drill 0.249936)
			(layers "*.Cu" "*.Mask")
			(remove_unused_layers no)
			(net "T1_GND")
			(clearance 0.10795)
			(padstack
				(mode front_inner_back)
				(layer "Inner"
					(shape circle)
					(size 0.8001 0.8001)
					(clearance 0.1524)
				)
				(layer "B.Cu"
					(shape circle)
					(size 1.9939 1.9939)
					(thermal_gap 0.10795)
					(clearance 0.10795)
				)
			)
		)
		(pad "3" thru_hole circle
			(at -2.54 2.54 90)
			(size 1.9939 1.9939)
			(drill 0.249936)
			(layers "*.Cu" "*.Mask")
			(remove_unused_layers no)
			(net "T1_GND")
			(clearance 0.10795)
			(padstack
				(mode front_inner_back)
				(layer "Inner"
					(shape circle)
					(size 0.8001 0.8001)
					(clearance 0.1524)
				)
				(layer "B.Cu"
					(shape circle)
					(size 1.9939 1.9939)
					(thermal_gap 0.10795)
					(clearance 0.10795)
				)
			)
		)
		(pad "4" thru_hole circle
			(at 0 2.54 90)
			(size 1.0033 1.0033)
			(drill 0.249936)
			(layers "*.Cu" "*.Mask")
			(remove_unused_layers no)
			(net "TDR_DIFF_100_IN5_DN")
			(clearance 0.10795)
			(padstack
				(mode front_inner_back)
				(layer "Inner"
					(shape circle)
					(size 0.8001 0.8001)
					(clearance 0.1524)
				)
				(layer "B.Cu"
					(shape circle)
					(size 1.0033 1.0033)
					(thermal_gap 0.10795)
					(clearance 0.10795)
				)
			)
		)
	)
	(footprint ""
		(layer "B.Cu")
		(at 315.569092 -191.215518 90)
		(property "Reference" "R4388"
			(at 0 0 90)
			(layer "B.SilkS")
			(hide yes)
			(effects
				(font
					(size 1.27 1.27)
				)
				(justify mirror)
			)
		)
		(property "Value" ""
			(at 0 0 90)
			(layer "B.Fab")
			(effects
				(font
					(size 1.27 1.27)
				)
				(justify mirror)
			)
		)
		(duplicate_pad_numbers_are_jumpers no)
		(fp_line
			(start 0.7874 -0.4064)
			(end -0.7874 -0.4064)
			(stroke
				(width 0.1524)
				(type default)
			)
			(layer "B.SilkS")
		)
		(fp_line
			(start -0.7874 -0.4064)
			(end -0.7874 0.4064)
			(stroke
				(width 0.1524)
				(type default)
			)
			(layer "B.SilkS")
		)
		(fp_line
			(start 0.7874 0.4064)
			(end 0.7874 -0.4064)
			(stroke
				(width 0.1524)
				(type default)
			)
			(layer "B.SilkS")
		)
		(fp_line
			(start -0.7874 0.4064)
			(end 0.7874 0.4064)
			(stroke
				(width 0.1524)
				(type default)
			)
			(layer "B.SilkS")
		)
		(fp_line
			(start 0.67945 -0.305054)
			(end 0.12065 -0.305054)
			(stroke
				(width 0.1)
				(type default)
			)
			(layer "B.Fab")
		)
		(fp_line
			(start 0.12065 -0.305054)
			(end 0.12065 -0.2794)
			(stroke
				(width 0.1)
				(type default)
			)
			(layer "B.Fab")
		)
		(fp_line
			(start -0.12065 -0.3048)
			(end -0.67945 -0.3048)
			(stroke
				(width 0.1)
				(type default)
			)
			(layer "B.Fab")
		)
		(fp_line
			(start -0.67945 -0.3048)
			(end -0.67945 0.3048)
			(stroke
				(width 0.1)
				(type default)
			)
			(layer "B.Fab")
		)
		(fp_line
			(start 0.12065 -0.2794)
			(end -0.12065 -0.2794)
			(stroke
				(width 0.1)
				(type default)
			)
			(layer "B.Fab")
		)
		(fp_line
			(start -0.12065 -0.2794)
			(end -0.12065 -0.3048)
			(stroke
				(width 0.1)
				(type default)
			)
			(layer "B.Fab")
		)
		(fp_line
			(start 0.12065 0.2794)
			(end 0.12065 0.3048)
			(stroke
				(width 0.1)
				(type default)
			)
			(layer "B.Fab")
		)
		(fp_line
			(start -0.120396 0.2794)
			(end 0.12065 0.2794)
			(stroke
				(width 0.1)
				(type default)
			)
			(layer "B.Fab")
		)
		(fp_line
			(start 0.67945 0.3048)
			(end 0.67945 -0.305054)
			(stroke
				(width 0.1)
				(type default)
			)
			(layer "B.Fab")
		)
		(fp_line
			(start 0.12065 0.3048)
			(end 0.67945 0.3048)
			(stroke
				(width 0.1)
				(type default)
			)
			(layer "B.Fab")
		)
		(fp_line
			(start -0.120396 0.3048)
			(end -0.120396 0.2794)
			(stroke
				(width 0.1)
				(type default)
			)
			(layer "B.Fab")
		)
		(fp_line
			(start -0.67945 0.3048)
			(end -0.120396 0.3048)
			(stroke
				(width 0.1)
				(type default)
			)
			(layer "B.Fab")
		)
		(pad "1" smd circle
			(at 0.40005 0 270)
			(size 0 0)
			(layers "B.Cu" "B.Mask" "B.Paste")
			(net "PVNN_TERM_CPU0")
		)
		(pad "2" smd circle
			(at -0.40005 0 270)
			(size 0 0)
			(layers "B.Cu" "B.Mask" "B.Paste")
			(net "H_CPU_ERR1_LVC1_R_N")
		)
	)
)
